# S9S_MB_2U (Grand Teton) — schematic netlist excerpt (pin names and nets, part order shuffled) for the footprints in the layout excerpt that follows; sources: Cadence DE-HDL packaged netlist, KiCad conversion of 03242023_DA0F0TMBIJ0_F0T_Motherboard_J_brd_V01_OCP.brd

H111  GND_HOLE  EMPTY  pkg TH  page 311
  GND2  = GND
  GND3  = GND
  GND4  = GND
  GND5  = GND
  GND6  = GND
  GND7  = GND
  GND8  = GND
  GND9  = GND

(kicad_pcb
	(version 20260206)
	(generator "pcbnew")
	(generator_version "10.0")
	(general
		(thickness 1.6)
		(legacy_teardrops no)
	)
	(paper "A4")
	(title_block
		(title "03242023_DA0F0TMBIJ0_F0T_Motherboard_J_brd_V01_OCP.brd")
		(comment 1 "Grand Teton / footprints 3158-3158 of 6105")
	)
	(layers
		(0 "F.Cu" signal "TOP")
		(4 "In1.Cu" signal "GND")
		(6 "In2.Cu" signal "IN1")
		(8 "In3.Cu" signal "GND1")
		(10 "In4.Cu" signal "IN2")
		(12 "In5.Cu" signal "GND2")
		(14 "In6.Cu" signal "IN3")
		(16 "In7.Cu" signal "GND3")
		(18 "In8.Cu" signal "VCC")
		(20 "In9.Cu" signal "VCC1")
		(22 "In10.Cu" signal "GND4")
		(24 "In11.Cu" signal "IN4")
		(26 "In12.Cu" signal "GND5")
		(28 "In13.Cu" signal "IN5")
		(30 "In14.Cu" signal "GND6")
		(32 "In15.Cu" signal "IN6")
		(34 "In16.Cu" signal "GND7")
		(2 "B.Cu" signal "BOTTOM")
		(9 "F.Adhes" user "F.Adhesive")
		(11 "B.Adhes" user "B.Adhesive")
		(13 "F.Paste" user "Package Geometry/Pastemask Top")
		(15 "B.Paste" user "Package Geometry/Pastemask Bottom")
		(5 "F.SilkS" user "Ref Des/Silkscreen Top")
		(7 "B.SilkS" user "Ref Des/Silkscreen Bottom")
		(1 "F.Mask" user "Board Geometry/Soldermask Top")
		(3 "B.Mask" user "Board Geometry/Soldermask Bottom")
		(17 "Dwgs.User" user "User.Drawings")
		(19 "Cmts.User" user "User.Comments")
		(21 "Eco1.User" user "User.Eco1")
		(23 "Eco2.User" user "User.Eco2")
		(25 "Edge.Cuts" user "Board Geometry/Outline")
		(27 "Margin" user)
		(31 "F.CrtYd" user "Package Geometry/Place Bound Top")
		(29 "B.CrtYd" user "Package Geometry/Place Bound Bottom")
		(35 "F.Fab" user "Ref Des/Assembly Top")
		(33 "B.Fab" user "Ref Des/Assembly Bottom")
	)
	(footprint ""
		(layer "F.Cu")
		(at 268.645132 -51.999896)
		(property "Reference" "H111"
			(at -9.58596 -6.67131 0)
			(unlocked yes)
			(layer "F.SilkS")
			(effects
				(font
					(size 0.7874 0.5842)
					(thickness 0.1524)
				)
				(justify left)
			)
		)
		(property "Value" ""
			(at 0 0 0)
			(layer "F.Fab")
			(effects
				(font
					(size 1.27 1.27)
				)
			)
		)
		(duplicate_pad_numbers_are_jumpers no)
		(fp_circle
			(center 0 0)
			(end 7.999984 0)
			(stroke
				(width 0.1524)
				(type default)
			)
			(fill no)
			(layer "F.SilkS")
		)
		(fp_circle
			(center 0 0)
			(end 7.999984 0)
			(stroke
				(width 0.1524)
				(type default)
			)
			(fill no)
			(layer "B.SilkS")
		)
		(fp_circle
			(center 0 0)
			(end 7.999984 0)
			(stroke
				(width 0.1)
				(type default)
			)
			(fill no)
			(layer "B.Fab")
		)
		(fp_circle
			(center 0 0)
			(end 7.999984 0)
			(stroke
				(width 0.1)
				(type default)
			)
			(fill no)
			(layer "F.Fab")
		)
		(pad "" np_thru_hole circle
			(at 0 0)
			(size 5.5118 5.5118)
			(drill 5.5118)
			(layers "*.Cu" "*.Mask")
			(clearance 0.381)
			(thermal_gap 0.381)
		)
		(pad "2" thru_hole circle
			(at 0 -3.999992)
			(size 0.762 0.762)
			(drill 0.5588)
			(layers "*.Cu" "*.Mask")
			(remove_unused_layers no)
			(net "GND")
			(clearance 0.1524)
			(thermal_gap 0.1524)
		)
		(pad "3" thru_hole circle
			(at -2.999994 -2.500122)
			(size 0.762 0.762)
			(drill 0.5588)
			(layers "*.Cu" "*.Mask")
			(remove_unused_layers no)
			(net "GND")
			(clearance 0.1524)
			(thermal_gap 0.1524)
		)
		(pad "4" thru_hole circle
			(at -3.999992 0)
			(size 0.762 0.762)
			(drill 0.5588)
			(layers "*.Cu" "*.Mask")
			(remove_unused_layers no)
			(net "GND")
			(clearance 0.1524)
			(thermal_gap 0.1524)
		)
		(pad "5" thru_hole circle
			(at -2.999994 2.500122)
			(size 0.762 0.762)
			(drill 0.5588)
			(layers "*.Cu" "*.Mask")
			(remove_unused_layers no)
			(net "GND")
			(clearance 0.1524)
			(thermal_gap 0.1524)
		)
		(pad "6" thru_hole circle
			(at 0 3.999992)
			(size 0.762 0.762)
			(drill 0.5588)
			(layers "*.Cu" "*.Mask")
			(remove_unused_layers no)
			(net "GND")
			(clearance 0.1524)
			(thermal_gap 0.1524)
		)
		(pad "7" thru_hole circle
			(at 2.999994 2.500122)
			(size 0.762 0.762)
			(drill 0.5588)
			(layers "*.Cu" "*.Mask")
			(remove_unused_layers no)
			(net "GND")
			(clearance 0.1524)
			(thermal_gap 0.1524)
		)
		(pad "8" thru_hole circle
			(at 3.999992 0)
			(size 0.762 0.762)
			(drill 0.5588)
			(layers "*.Cu" "*.Mask")
			(remove_unused_layers no)
			(net "GND")
			(clearance 0.1524)
			(thermal_gap 0.1524)
		)
		(pad "9" thru_hole circle
			(at 2.999994 -2.500122)
			(size 0.762 0.762)
			(drill 0.5588)
			(layers "*.Cu" "*.Mask")
			(remove_unused_layers no)
			(net "GND")
			(clearance 0.1524)
			(thermal_gap 0.1524)
		)
		(zone
			(layer "F.Cu")
			(hatch none 0.5)
			(connect_pads
				(clearance 0)
			)
			(min_thickness 0.25)
			(keepout
				(tracks not_allowed)
				(vias allowed)
				(pads allowed)
				(copperpour not_allowed)
				(footprints allowed)
			)
			(placement
				(enabled no)
				(sheetname "")
			)
			(fill
				(thermal_gap 0.5)
				(thermal_bridge_width 0.5)
				(island_removal_mode 0)
			)
			(polygon
				(pts
					(arc
						(start 268.645132 -59.99988)
						(mid 262.988289 -57.656739)
						(end 260.645148 -51.999896)
					)
					(arc
						(start 260.645148 -51.999896)
						(mid 262.988289 -46.343053)
						(end 268.645132 -43.999912)
					)
					(xy 268.645132 -46.74616) (xy 268.594078 -46.74616)
					(arc
						(start 268.593824 -46.74616)
						(mid 263.391145 -51.999896)
						(end 268.593824 -57.253632)
					)
					(xy 268.594078 -57.253632) (xy 268.645132 -57.253632)
				)
			)
		)
		(zone
			(layer "F.Cu")
			(hatch none 0.5)
			(connect_pads
				(clearance 0)
			)
			(min_thickness 0.25)
			(keepout
				(tracks not_allowed)
				(vias allowed)
				(pads allowed)
				(copperpour not_allowed)
				(footprints allowed)
			)
			(placement
				(enabled no)
				(sheetname "")
			)
			(fill
				(thermal_gap 0.5)
				(thermal_bridge_width 0.5)
				(island_removal_mode 0)
			)
			(polygon
				(pts
					(arc
						(start 268.645132 -59.99988)
						(mid 274.301975 -57.656739)
						(end 276.645116 -51.999896)
					)
					(arc
						(start 276.645116 -51.999896)
						(mid 274.301975 -46.343053)
						(end 268.645132 -43.999912)
					)
					(xy 268.645132 -46.74616) (xy 268.696186 -46.74616)
					(arc
						(start 268.69644 -46.74616)
						(mid 273.899119 -51.999896)
						(end 268.69644 -57.253632)
					)
					(xy 268.696186 -57.253632) (xy 268.645132 -57.253632)
				)
			)
		)
		(zone
			(layers "F.Cu" "B.Cu" "In1.Cu" "In2.Cu" "In3.Cu" "In4.Cu" "In5.Cu" "In6.Cu"
				"In7.Cu" "In8.Cu" "In9.Cu" "In10.Cu" "In11.Cu" "In12.Cu" "In13.Cu" "In14.Cu"
				"In15.Cu" "In16.Cu"
			)
			(hatch none 0.5)
			(connect_pads
				(clearance 0)
			)
			(min_thickness 0.25)
			(keepout
				(tracks not_allowed)
				(vias allowed)
				(pads allowed)
				(copperpour not_allowed)
				(footprints allowed)
			)
			(placement
				(enabled no)
				(sheetname "")
			)
			(fill
				(thermal_gap 0.5)
				(thermal_bridge_width 0.5)
				(island_removal_mode 0)
			)
			(polygon
				(pts
					(arc
						(start 271.921732 -51.999896)
						(mid 265.368532 -51.999896)
						(end 271.921732 -51.999896)
					)
				)
			)
		)
		(zone
			(layer "B.Cu")
			(hatch none 0.5)
			(connect_pads
				(clearance 0)
			)
			(min_thickness 0.25)
			(keepout
				(tracks not_allowed)
				(vias allowed)
				(pads allowed)
				(copperpour not_allowed)
				(footprints allowed)
			)
			(placement
				(enabled no)
				(sheetname "")
			)
			(fill
				(thermal_gap 0.5)
				(thermal_bridge_width 0.5)
				(island_removal_mode 0)
			)
			(polygon
				(pts
					(arc
						(start 268.645132 -57.507886)
						(mid 263.137142 -51.999896)
						(end 268.645132 -46.491906)
					)
					(arc
						(start 268.645132 -46.974506)
						(mid 263.619742 -51.999896)
						(end 268.645132 -57.025286)
					)
				)
			)
		)
		(zone
			(layer "B.Cu")
			(hatch none 0.5)
			(connect_pads
				(clearance 0)
			)
			(min_thickness 0.25)
			(keepout
				(tracks not_allowed)
				(vias allowed)
				(pads allowed)
				(copperpour not_allowed)
				(footprints allowed)
			)
			(placement
				(enabled no)
				(sheetname "")
			)
			(fill
				(thermal_gap 0.5)
				(thermal_bridge_width 0.5)
				(island_removal_mode 0)
			)
			(polygon
				(pts
					(arc
						(start 268.645132 -57.507886)
						(mid 274.153122 -51.999896)
						(end 268.645132 -46.491906)
					)
					(arc
						(start 268.645132 -46.974506)
						(mid 273.670522 -51.999896)
						(end 268.645132 -57.025286)
					)
				)
			)
		)
	)
)
